M48
INCH,TZ
T01C.012
T02C.086
T03C.101
T04C.115
;EXTENTS: -103.588 -109.012 119.885 108.098 
;LEADER: 12 
;HEADER: 
;CODE  : ASCII 
;FILE  : 16347-sc.rou for board 16347-sc.brd
%
G90
F1
M16
G40
M30
